# T6G (Grand Teton) — schematic netlist excerpt (pin names and nets, part order shuffled) for the footprints in the layout excerpt that follows; sources: Cadence DE-HDL packaged netlist, KiCad conversion of 04192023_DAF0TMB3IC0_F0TG_MB_C_brd_V02_OCP.brd

R3461  Q_RES  54.9K 1% CHIP  pkg 0402LF  page 129 : A = P3V3_AUX ; B = GPU_NVS_PWR_BRAKE_N_R
PR3835  Q_RES  14.3K 1% CHIP  pkg 0402LF  page 135 : A = P12V_OCP_ISET_1 ; B = GND

(kicad_pcb
	(version 20260206)
	(generator "pcbnew")
	(generator_version "10.0")
	(general
		(thickness 1.6)
		(legacy_teardrops no)
	)
	(paper "A4")
	(title_block
		(title "04192023_DAF0TMB3IC0_F0TG_MB_C_brd_V02_OCP.brd")
		(comment 1 "Grand Teton / footprints 2580-2581 of 8354")
	)
	(layers
		(0 "F.Cu" signal "TOP")
		(4 "In1.Cu" signal "GND")
		(6 "In2.Cu" signal "IN1")
		(8 "In3.Cu" signal "GND1")
		(10 "In4.Cu" signal "IN2")
		(12 "In5.Cu" signal "GND2")
		(14 "In6.Cu" signal "IN3")
		(16 "In7.Cu" signal "GND3")
		(18 "In8.Cu" signal "VCC")
		(20 "In9.Cu" signal "VCC1")
		(22 "In10.Cu" signal "GND4")
		(24 "In11.Cu" signal "IN4")
		(26 "In12.Cu" signal "GND5")
		(28 "In13.Cu" signal "IN5")
		(30 "In14.Cu" signal "GND6")
		(32 "In15.Cu" signal "IN6")
		(34 "In16.Cu" signal "GND7")
		(2 "B.Cu" signal "BOTTOM")
		(9 "F.Adhes" user "F.Adhesive")
		(11 "B.Adhes" user "B.Adhesive")
		(13 "F.Paste" user "Package Geometry/Pastemask Top")
		(15 "B.Paste" user "Package Geometry/Pastemask Bottom")
		(5 "F.SilkS" user "Ref Des/Silkscreen Top")
		(7 "B.SilkS" user "Ref Des/Silkscreen Bottom")
		(1 "F.Mask" user "Board Geometry/Soldermask Top")
		(3 "B.Mask" user "Board Geometry/Soldermask Bottom")
		(17 "Dwgs.User" user "User.Drawings")
		(19 "Cmts.User" user "User.Comments")
		(21 "Eco1.User" user "User.Eco1")
		(23 "Eco2.User" user "User.Eco2")
		(25 "Edge.Cuts" user "Board Geometry/Outline")
		(27 "Margin" user)
		(31 "F.CrtYd" user "Package Geometry/Place Bound Top")
		(29 "B.CrtYd" user "Package Geometry/Place Bound Bottom")
		(35 "F.Fab" user "Ref Des/Assembly Top")
		(33 "B.Fab" user "Ref Des/Assembly Bottom")
	)
	(footprint ""
		(layer "F.Cu")
		(at 442.828172 -33.062418 90)
		(property "Reference" "PR3835"
			(at 0 0 90)
			(layer "F.SilkS")
			(hide yes)
			(effects
				(font
					(size 1.27 1.27)
				)
			)
		)
		(property "Value" ""
			(at 0 0 90)
			(layer "F.Fab")
			(effects
				(font
					(size 1.27 1.27)
				)
			)
		)
		(duplicate_pad_numbers_are_jumpers no)
		(fp_line
			(start 0.7874 -0.4064)
			(end 0.7874 0.4064)
			(stroke
				(width 0.1524)
				(type default)
			)
			(layer "F.SilkS")
		)
		(fp_line
			(start -0.7874 -0.4064)
			(end 0.7874 -0.4064)
			(stroke
				(width 0.1524)
				(type default)
			)
			(layer "F.SilkS")
		)
		(fp_line
			(start 0.7874 0.4064)
			(end -0.7874 0.4064)
			(stroke
				(width 0.1524)
				(type default)
			)
			(layer "F.SilkS")
		)
		(fp_line
			(start -0.7874 0.4064)
			(end -0.7874 -0.4064)
			(stroke
				(width 0.1524)
				(type default)
			)
			(layer "F.SilkS")
		)
		(fp_line
			(start -0.12065 -0.305054)
			(end -0.12065 -0.2794)
			(stroke
				(width 0.1)
				(type default)
			)
			(layer "F.Fab")
		)
		(fp_line
			(start -0.67945 -0.305054)
			(end -0.12065 -0.305054)
			(stroke
				(width 0.1)
				(type default)
			)
			(layer "F.Fab")
		)
		(fp_line
			(start 0.67945 -0.3048)
			(end 0.67945 0.3048)
			(stroke
				(width 0.1)
				(type default)
			)
			(layer "F.Fab")
		)
		(fp_line
			(start 0.12065 -0.3048)
			(end 0.67945 -0.3048)
			(stroke
				(width 0.1)
				(type default)
			)
			(layer "F.Fab")
		)
		(fp_line
			(start 0.12065 -0.2794)
			(end 0.12065 -0.3048)
			(stroke
				(width 0.1)
				(type default)
			)
			(layer "F.Fab")
		)
		(fp_line
			(start -0.12065 -0.2794)
			(end 0.12065 -0.2794)
			(stroke
				(width 0.1)
				(type default)
			)
			(layer "F.Fab")
		)
		(fp_line
			(start 0.120396 0.2794)
			(end -0.12065 0.2794)
			(stroke
				(width 0.1)
				(type default)
			)
			(layer "F.Fab")
		)
		(fp_line
			(start -0.12065 0.2794)
			(end -0.12065 0.3048)
			(stroke
				(width 0.1)
				(type default)
			)
			(layer "F.Fab")
		)
		(fp_line
			(start 0.67945 0.3048)
			(end 0.120396 0.3048)
			(stroke
				(width 0.1)
				(type default)
			)
			(layer "F.Fab")
		)
		(fp_line
			(start 0.120396 0.3048)
			(end 0.120396 0.2794)
			(stroke
				(width 0.1)
				(type default)
			)
			(layer "F.Fab")
		)
		(fp_line
			(start -0.12065 0.3048)
			(end -0.67945 0.3048)
			(stroke
				(width 0.1)
				(type default)
			)
			(layer "F.Fab")
		)
		(fp_line
			(start -0.67945 0.3048)
			(end -0.67945 -0.305054)
			(stroke
				(width 0.1)
				(type default)
			)
			(layer "F.Fab")
		)
		(pad "1" smd circle
			(at -0.40005 0 90)
			(size 0 0)
			(layers "F.Cu" "F.Mask" "F.Paste")
			(net "P12V_OCP_ISET_1")
		)
		(pad "2" smd circle
			(at 0.40005 0 90)
			(size 0 0)
			(layers "F.Cu" "F.Mask" "F.Paste")
			(net "GND")
		)
	)
	(footprint ""
		(layer "F.Cu")
		(at 105.537 -421.005)
		(property "Reference" "R3461"
			(at 0 0 0)
			(layer "F.SilkS")
			(hide yes)
			(effects
				(font
					(size 1.27 1.27)
				)
			)
		)
		(property "Value" ""
			(at 0 0 0)
			(layer "F.Fab")
			(effects
				(font
					(size 1.27 1.27)
				)
			)
		)
		(duplicate_pad_numbers_are_jumpers no)
		(fp_line
			(start -0.7874 -0.4064)
			(end 0.7874 -0.4064)
			(stroke
				(width 0.1524)
				(type default)
			)
			(layer "F.SilkS")
		)
		(fp_line
			(start -0.7874 0.4064)
			(end -0.7874 -0.4064)
			(stroke
				(width 0.1524)
				(type default)
			)
			(layer "F.SilkS")
		)
		(fp_line
			(start 0.7874 -0.4064)
			(end 0.7874 0.4064)
			(stroke
				(width 0.1524)
				(type default)
			)
			(layer "F.SilkS")
		)
		(fp_line
			(start 0.7874 0.4064)
			(end -0.7874 0.4064)
			(stroke
				(width 0.1524)
				(type default)
			)
			(layer "F.SilkS")
		)
		(fp_line
			(start -0.67945 -0.305054)
			(end -0.12065 -0.305054)
			(stroke
				(width 0.1)
				(type default)
			)
			(layer "F.Fab")
		)
		(fp_line
			(start -0.67945 0.3048)
			(end -0.67945 -0.305054)
			(stroke
				(width 0.1)
				(type default)
			)
			(layer "F.Fab")
		)
		(fp_line
			(start -0.12065 -0.305054)
			(end -0.12065 -0.2794)
			(stroke
				(width 0.1)
				(type default)
			)
			(layer "F.Fab")
		)
		(fp_line
			(start -0.12065 -0.2794)
			(end 0.12065 -0.2794)
			(stroke
				(width 0.1)
				(type default)
			)
			(layer "F.Fab")
		)
		(fp_line
			(start -0.12065 0.2794)
			(end -0.12065 0.3048)
			(stroke
				(width 0.1)
				(type default)
			)
			(layer "F.Fab")
		)
		(fp_line
			(start -0.12065 0.3048)
			(end -0.67945 0.3048)
			(stroke
				(width 0.1)
				(type default)
			)
			(layer "F.Fab")
		)
		(fp_line
			(start 0.120396 0.2794)
			(end -0.12065 0.2794)
			(stroke
				(width 0.1)
				(type default)
			)
			(layer "F.Fab")
		)
		(fp_line
			(start 0.120396 0.3048)
			(end 0.120396 0.2794)
			(stroke
				(width 0.1)
				(type default)
			)
			(layer "F.Fab")
		)
		(fp_line
			(start 0.12065 -0.3048)
			(end 0.67945 -0.3048)
			(stroke
				(width 0.1)
				(type default)
			)
			(layer "F.Fab")
		)
		(fp_line
			(start 0.12065 -0.2794)
			(end 0.12065 -0.3048)
			(stroke
				(width 0.1)
				(type default)
			)
			(layer "F.Fab")
		)
		(fp_line
			(start 0.67945 -0.3048)
			(end 0.67945 0.3048)
			(stroke
				(width 0.1)
				(type default)
			)
			(layer "F.Fab")
		)
		(fp_line
			(start 0.67945 0.3048)
			(end 0.120396 0.3048)
			(stroke
				(width 0.1)
				(type default)
			)
			(layer "F.Fab")
		)
		(pad "1" smd circle
			(at -0.40005 0)
			(size 0 0)
			(layers "F.Cu" "F.Mask" "F.Paste")
			(net "P3V3_AUX")
		)
		(pad "2" smd circle
			(at 0.40005 0)
			(size 0 0)
			(layers "F.Cu" "F.Mask" "F.Paste")
			(net "GPU_NVS_PWR_BRAKE_N_R")
		)
	)
)
